FILE_TYPE = CONNECTIVITY;
{Allegro Design Entry HDL 17.4-2019 S026 (4007227) 1/17/2022}
"PAGE_NUMBER" = 73;
0"NC";
1"GND\g";
2"PVDDCR_SOC_P1\g";
3"GND\g";
4"PVDDCR_SOC_P1\g";
5"GND\g";
6"PVDDCR_SOC_P1\g";
7"GND\g";
8"PVDDCR_SOC_P1\g";
9"GND\g";
10"PVDDCR_SOC_P1\g";
11"PVDDCR_SOC_P1\g";
12"GND\g";
13"GND\g";
14"PVDDCR_SOC_P1\g";
15"GND\g";
16"PVDDCR_SOC_P1\g";
17"GND\g";
18"PVDD11_S3_P1\g";
19"GND\g";
20"PVDD11_S3_P1\g";
21"GND\g";
22"PVDD11_S3_P1\g";
23"GND\g";
24"PVDD11_S3_P1\g";
25"GND\g";
26"PVDD11_S3_P1\g";
27"GND\g";
28"PVDDIO_P1\g";
29"GND\g";
30"PVDDIO_P1\g";
31"GND\g";
32"PVDDIO_P1\g";
%"Q_CAP"
"1","(400,1075)","0","pure_quanta","I1";
;
LOCATION"C3912"
$SEC"1"
CDS_SEC"1"
MATERIAL"X6S"
TOLERANCE"20%"
VALUE"22UF"
VOLTAGE"4V"
PACK_TYPE"C0402"
CDS_LIB"pure_quanta"
PART_NUMBER"CH622KMEB02";
"B"
$PN"2"1;
"A"
$PN"1"4;
%"UNIVERSAL_POWER"
"1","(400,2075)","0","pure_quanta_power","I10";
;
HDL_POWER"PVDDCR_SOC_P1"
CDS_LIB"pure_quanta_power";
"A"2;
%"Q_CAP"
"1","(5450,2650)","0","pure_quanta","I100";
;
LOCATION"C2486"
$SEC"1"
CDS_SEC"1"
MATERIAL"X6S"
TOLERANCE"20%"
VALUE"22UF"
VOLTAGE"4V"
PACK_TYPE"C0402"
CDS_LIB"pure_quanta"
PART_NUMBER"CH622KMEB02";
"B"
$PN"2"25;
"A"
$PN"1"24;
%"Q_CAP"
"1","(5900,2025)","0","pure_quanta","I101";
;
LOCATION"C2491"
$SEC"1"
CDS_SEC"1"
MATERIAL"X6S"
TOLERANCE"20%"
VALUE"22UF"
VOLTAGE"4V"
PACK_TYPE"C0402"
CDS_LIB"pure_quanta"
PART_NUMBER"CH622KMEB02";
"B"
$PN"2"17;
"A"
$PN"1"26;
%"Q_CAP"
"1","(5900,2650)","0","pure_quanta","I102";
;
LOCATION"C2490"
$SEC"1"
CDS_SEC"1"
MATERIAL"X6S"
TOLERANCE"20%"
VALUE"22UF"
VOLTAGE"4V"
PACK_TYPE"C0402"
CDS_LIB"pure_quanta"
PART_NUMBER"CH622KMEB02";
"B"
$PN"2"25;
"A"
$PN"1"24;
%"Q_CAP"
"1","(5450,3325)","0","pure_quanta","I103";
;
LOCATION"C2485"
$SEC"1"
CDS_SEC"1"
MATERIAL"X6S"
TOLERANCE"20%"
VALUE"22UF"
VOLTAGE"4V"
PACK_TYPE"C0402"
CDS_LIB"pure_quanta"
PART_NUMBER"CH622KMEB02";
"B"
$PN"2"23;
"A"
$PN"1"22;
%"Q_CAP"
"1","(5900,3325)","0","pure_quanta","I104";
;
LOCATION"C2489"
$SEC"1"
CDS_SEC"1"
MATERIAL"X6S"
TOLERANCE"20%"
VALUE"22UF"
VOLTAGE"4V"
PACK_TYPE"C0402"
CDS_LIB"pure_quanta"
PART_NUMBER"CH622KMEB02";
"B"
$PN"2"23;
"A"
$PN"1"22;
%"Q_CAP"
"1","(6350,1375)","0","pure_quanta","I105";
;
LOCATION"C2497"
$SEC"1"
CDS_SEC"1"
MATERIAL"X6S"
TOLERANCE"20%"
VALUE"22UF"
VOLTAGE"4V"
PACK_TYPE"C0402"
CDS_LIB"pure_quanta"
PART_NUMBER"CH622KMEB02";
"B"
$PN"2"19;
"A"
$PN"1"18;
%"Q_CAP"
"1","(6800,1375)","0","pure_quanta","I106";
;
LOCATION"C2502"
$SEC"1"
CDS_SEC"1"
MATERIAL"X6S"
TOLERANCE"20%"
VALUE"22UF"
VOLTAGE"4V"
PACK_TYPE"C0402"
CDS_LIB"pure_quanta"
PART_NUMBER"CH622KMEB02";
"B"
$PN"2"19;
"A"
$PN"1"18;
%"Q_CAP"
"1","(7250,1375)","0","pure_quanta","I107";
;
LOCATION"C2506"
$SEC"1"
CDS_SEC"1"
MATERIAL"X6S"
TOLERANCE"20%"
VALUE"22UF"
VOLTAGE"4V"
PACK_TYPE"C0402"
CDS_LIB"pure_quanta"
PART_NUMBER"CH622KMEB02";
"B"
$PN"2"19;
"A"
$PN"1"18;
%"Q_CAP"
"1","(7700,1375)","0","pure_quanta","I108";
;
LOCATION"C2115"
$SEC"1"
CDS_SEC"1"
MATERIAL"X6S"
TOLERANCE"20%"
VALUE"22UF"
VOLTAGE"4V"
PACK_TYPE"C0402"
CDS_LIB"pure_quanta"
PART_NUMBER"CH622KMEB02";
"B"
$PN"2"19;
"A"
$PN"1"18;
%"Q_CAP"
"1","(8150,1375)","0","pure_quanta","I109";
;
LOCATION"C2121"
$SEC"1"
CDS_SEC"1"
MATERIAL"X6S"
TOLERANCE"20%"
VALUE"22UF"
VOLTAGE"4V"
PACK_TYPE"C0402"
CDS_LIB"pure_quanta"
PART_NUMBER"CH622KMEB02";
"B"
$PN"2"19;
"A"
$PN"1"18;
%"Q_CAP"
"1","(400,2475)","0","pure_quanta","I11";
;
LOCATION"C2412"
$SEC"1"
CDS_SEC"1"
MATERIAL"X6S"
TOLERANCE"20%"
VALUE"22UF"
VOLTAGE"4V"
PACK_TYPE"C0402"
CDS_LIB"pure_quanta"
PART_NUMBER"CH622KMEB02";
"B"
$PN"2"7;
"A"
$PN"1"6;
%"Q_CAP"
"1","(6350,2025)","0","pure_quanta","I110";
;
LOCATION"C2496"
$SEC"1"
CDS_SEC"1"
MATERIAL"X6S"
TOLERANCE"20%"
VALUE"22UF"
VOLTAGE"4V"
PACK_TYPE"C0402"
CDS_LIB"pure_quanta"
PART_NUMBER"CH622KMEB02";
"B"
$PN"2"17;
"A"
$PN"1"26;
%"Q_CAP"
"1","(6350,2650)","0","pure_quanta","I111";
;
LOCATION"C2495"
$SEC"1"
CDS_SEC"1"
MATERIAL"X6S"
TOLERANCE"20%"
VALUE"22UF"
VOLTAGE"4V"
PACK_TYPE"C0402"
CDS_LIB"pure_quanta"
PART_NUMBER"CH622KMEB02";
"B"
$PN"2"25;
"A"
$PN"1"24;
%"Q_CAP"
"1","(6800,2025)","0","pure_quanta","I112";
;
LOCATION"C2501"
$SEC"1"
CDS_SEC"1"
MATERIAL"X6S"
TOLERANCE"20%"
VALUE"22UF"
VOLTAGE"4V"
PACK_TYPE"C0402"
CDS_LIB"pure_quanta"
PART_NUMBER"CH622KMEB02";
"B"
$PN"2"17;
"A"
$PN"1"26;
%"Q_CAP"
"1","(6800,2650)","0","pure_quanta","I113";
;
LOCATION"C2500"
$SEC"1"
CDS_SEC"1"
MATERIAL"X6S"
TOLERANCE"20%"
VALUE"22UF"
VOLTAGE"4V"
PACK_TYPE"C0402"
CDS_LIB"pure_quanta"
PART_NUMBER"CH622KMEB02";
"B"
$PN"2"25;
"A"
$PN"1"24;
%"Q_CAP"
"1","(6350,3325)","0","pure_quanta","I114";
;
LOCATION"C2494"
$SEC"1"
CDS_SEC"1"
MATERIAL"X6S"
TOLERANCE"20%"
VALUE"22UF"
VOLTAGE"4V"
PACK_TYPE"C0402"
CDS_LIB"pure_quanta"
PART_NUMBER"CH622KMEB02";
"B"
$PN"2"23;
"A"
$PN"1"22;
%"UNIVERSAL_GND"
"1","(6350,3925)","0","pure_quanta_power","I115";
;
CDS_LIB"pure_quanta_power"
HDL_POWER"GND";
"A"27;
%"Q_CAP"
"1","(6800,3325)","0","pure_quanta","I116";
;
LOCATION"C2499"
$SEC"1"
CDS_SEC"1"
MATERIAL"X6S"
TOLERANCE"20%"
VALUE"22UF"
VOLTAGE"4V"
PACK_TYPE"C0402"
CDS_LIB"pure_quanta"
PART_NUMBER"CH622KMEB02";
"B"
$PN"2"23;
"A"
$PN"1"22;
%"Q_CAP"
"1","(7250,2025)","0","pure_quanta","I117";
;
LOCATION"C2505"
$SEC"1"
CDS_SEC"1"
MATERIAL"X6S"
TOLERANCE"20%"
VALUE"22UF"
VOLTAGE"4V"
PACK_TYPE"C0402"
CDS_LIB"pure_quanta"
PART_NUMBER"CH622KMEB02";
"B"
$PN"2"17;
"A"
$PN"1"26;
%"Q_CAP"
"1","(7250,2650)","0","pure_quanta","I118";
;
LOCATION"C2504"
$SEC"1"
CDS_SEC"1"
MATERIAL"X6S"
TOLERANCE"20%"
VALUE"22UF"
VOLTAGE"4V"
PACK_TYPE"C0402"
CDS_LIB"pure_quanta"
PART_NUMBER"CH622KMEB02";
"B"
$PN"2"25;
"A"
$PN"1"24;
%"Q_CAP"
"1","(7700,2650)","0","pure_quanta","I119";
;
LOCATION"C2113"
$SEC"1"
CDS_SEC"1"
MATERIAL"X6S"
TOLERANCE"20%"
VALUE"22UF"
VOLTAGE"4V"
PACK_TYPE"C0402"
CDS_LIB"pure_quanta"
PART_NUMBER"CH622KMEB02";
"B"
$PN"2"25;
"A"
$PN"1"24;
%"UNIVERSAL_POWER"
"1","(400,2750)","0","pure_quanta_power","I12";
;
HDL_POWER"PVDDCR_SOC_P1"
CDS_LIB"pure_quanta_power";
"A"6;
%"Q_CAP"
"1","(7700,2025)","0","pure_quanta","I120";
;
LOCATION"C2114"
$SEC"1"
CDS_SEC"1"
MATERIAL"X6S"
TOLERANCE"20%"
VALUE"22UF"
VOLTAGE"4V"
PACK_TYPE"C0402"
CDS_LIB"pure_quanta"
PART_NUMBER"CH622KMEB02";
"B"
$PN"2"17;
"A"
$PN"1"26;
%"Q_CAP"
"1","(8150,2025)","0","pure_quanta","I121";
;
LOCATION"C2120"
$SEC"1"
CDS_SEC"1"
MATERIAL"X6S"
TOLERANCE"20%"
VALUE"22UF"
VOLTAGE"4V"
PACK_TYPE"C0402"
CDS_LIB"pure_quanta"
PART_NUMBER"CH622KMEB02";
"B"
$PN"2"17;
"A"
$PN"1"26;
%"Q_CAP"
"1","(8150,2650)","0","pure_quanta","I122";
;
LOCATION"C2119"
$SEC"1"
CDS_SEC"1"
MATERIAL"X6S"
TOLERANCE"20%"
VALUE"22UF"
VOLTAGE"4V"
PACK_TYPE"C0402"
CDS_LIB"pure_quanta"
PART_NUMBER"CH622KMEB02";
"B"
$PN"2"25;
"A"
$PN"1"24;
%"Q_CAP"
"1","(7250,3325)","0","pure_quanta","I123";
;
LOCATION"C2503"
$SEC"1"
CDS_SEC"1"
MATERIAL"X6S"
TOLERANCE"20%"
VALUE"22UF"
VOLTAGE"4V"
PACK_TYPE"C0402"
CDS_LIB"pure_quanta"
PART_NUMBER"CH622KMEB02";
"B"
$PN"2"23;
"A"
$PN"1"22;
%"Q_CAP"
"1","(7700,3325)","0","pure_quanta","I124";
;
LOCATION"C2508"
$SEC"1"
CDS_SEC"1"
MATERIAL"X6S"
TOLERANCE"20%"
VALUE"22UF"
VOLTAGE"4V"
PACK_TYPE"C0402"
CDS_LIB"pure_quanta"
PART_NUMBER"CH622KMEB02";
"B"
$PN"2"23;
"A"
$PN"1"22;
%"Q_CAP"
"1","(8150,3325)","0","pure_quanta","I125";
;
LOCATION"C2118"
$SEC"1"
CDS_SEC"1"
MATERIAL"X6S"
TOLERANCE"20%"
VALUE"22UF"
VOLTAGE"4V"
PACK_TYPE"C0402"
CDS_LIB"pure_quanta"
PART_NUMBER"CH622KMEB02";
"B"
$PN"2"23;
"A"
$PN"1"22;
%"UNIVERSAL_GND"
"1","(4400,4175)","0","pure_quanta_power","I126";
;
CDS_LIB"pure_quanta_power"
HDL_POWER"GND";
"A"12;
%"Q_CAP"
"1","(4400,4550)","0","pure_quanta","I127";
;
LOCATION"C2472"
$SEC"1"
CDS_SEC"1"
MATERIAL"X6S"
TOLERANCE"20%"
VALUE"22UF"
VOLTAGE"4V"
PACK_TYPE"C0402"
CDS_LIB"pure_quanta"
PART_NUMBER"CH622KMEB02";
"B"
$PN"2"12;
"A"
$PN"1"11;
%"UNIVERSAL_GND"
"1","(4400,4850)","0","pure_quanta_power","I128";
;
CDS_LIB"pure_quanta_power"
HDL_POWER"GND";
"A"13;
%"Q_CAP"
"1","(5000,4300)","0","pure_quanta","I129";
;
LOCATION"C2479"
$SEC"1"
CDS_SEC"1"
MATERIAL"X6S"
TOLERANCE"20%"
VALUE"22UF"
VOLTAGE"4V"
PACK_TYPE"C0402"
CDS_LIB"pure_quanta"
PART_NUMBER"CH622KMEB02";
"B"
$PN"2"27;
"A"
$PN"1"32;
%"Q_CAP"
"1","(850,2475)","0","pure_quanta","I13";
;
LOCATION"C2419"
$SEC"1"
CDS_SEC"1"
MATERIAL"X6S"
TOLERANCE"20%"
VALUE"22UF"
VOLTAGE"4V"
PACK_TYPE"C0402"
CDS_LIB"pure_quanta"
PART_NUMBER"CH622KMEB02";
"B"
$PN"2"7;
"A"
$PN"1"6;
%"UNIVERSAL_POWER"
"1","(5000,4575)","0","pure_quanta_power","I130";
;
HDL_POWER"PVDDIO_P1"
CDS_LIB"pure_quanta_power";
"A"32;
%"Q_CAP"
"1","(4400,5225)","0","pure_quanta","I131";
;
LOCATION"C2471"
$SEC"1"
CDS_SEC"1"
MATERIAL"X6S"
TOLERANCE"20%"
VALUE"22UF"
VOLTAGE"4V"
PACK_TYPE"C0402"
CDS_LIB"pure_quanta"
PART_NUMBER"CH622KMEB02";
"B"
$PN"2"13;
"A"
$PN"1"16;
%"UNIVERSAL_GND"
"1","(4400,5500)","0","pure_quanta_power","I132";
;
CDS_LIB"pure_quanta_power"
HDL_POWER"GND";
"A"15;
%"Q_CAP"
"1","(4400,5875)","0","pure_quanta","I133";
;
LOCATION"C2470"
$SEC"1"
CDS_SEC"1"
MATERIAL"X6S"
TOLERANCE"20%"
VALUE"22UF"
VOLTAGE"4V"
PACK_TYPE"C0402"
CDS_LIB"pure_quanta"
PART_NUMBER"CH622KMEB02";
"B"
$PN"2"15;
"A"
$PN"1"14;
%"Q_CAP"
"1","(4975,5075)","0","pure_quanta","I134";
;
LOCATION"C2478"
$SEC"1"
CDS_SEC"1"
MATERIAL"X6S"
TOLERANCE"20%"
VALUE"22UF"
VOLTAGE"4V"
PACK_TYPE"C0402"
CDS_LIB"pure_quanta"
PART_NUMBER"CH622KMEB02";
"B"
$PN"2"31;
"A"
$PN"1"30;
%"UNIVERSAL_POWER"
"1","(4975,5350)","0","pure_quanta_power","I135";
;
HDL_POWER"PVDDIO_P1"
CDS_LIB"pure_quanta_power";
"A"30;
%"Q_CAP"
"1","(4975,5875)","0","pure_quanta","I136";
;
LOCATION"C2477"
$SEC"1"
CDS_SEC"1"
MATERIAL"X6S"
TOLERANCE"20%"
VALUE"22UF"
VOLTAGE"4V"
PACK_TYPE"C0402"
CDS_LIB"pure_quanta"
PART_NUMBER"CH622KMEB02";
"B"
$PN"2"29;
"A"
$PN"1"28;
%"Q_CAP"
"1","(5450,4300)","0","pure_quanta","I137";
;
LOCATION"C2103"
$SEC"1"
CDS_SEC"1"
MATERIAL"X6S"
TOLERANCE"20%"
VALUE"22UF"
VOLTAGE"4V"
PACK_TYPE"C0402"
CDS_LIB"pure_quanta"
PART_NUMBER"CH622KMEB02";
"B"
$PN"2"27;
"A"
$PN"1"32;
%"Q_CAP"
"1","(5900,4300)","0","pure_quanta","I138";
;
LOCATION"C2106"
$SEC"1"
CDS_SEC"1"
MATERIAL"X6S"
TOLERANCE"20%"
VALUE"22UF"
VOLTAGE"4V"
PACK_TYPE"C0402"
CDS_LIB"pure_quanta"
PART_NUMBER"CH622KMEB02";
"B"
$PN"2"27;
"A"
$PN"1"32;
%"Q_CAP"
"1","(5425,5075)","0","pure_quanta","I139";
;
LOCATION"C2484"
$SEC"1"
CDS_SEC"1"
MATERIAL"X6S"
TOLERANCE"20%"
VALUE"22UF"
VOLTAGE"4V"
PACK_TYPE"C0402"
CDS_LIB"pure_quanta"
PART_NUMBER"CH622KMEB02";
"B"
$PN"2"31;
"A"
$PN"1"30;
%"Q_CAP"
"1","(400,3150)","0","pure_quanta","I14";
;
LOCATION"C2411"
$SEC"1"
CDS_SEC"1"
MATERIAL"X6S"
TOLERANCE"20%"
VALUE"22UF"
VOLTAGE"4V"
PACK_TYPE"C0402"
CDS_LIB"pure_quanta"
PART_NUMBER"CH622KMEB02";
"B"
$PN"2"5;
"A"
$PN"1"10;
%"Q_CAP"
"1","(5425,5875)","0","pure_quanta","I140";
;
LOCATION"C2102"
$SEC"1"
CDS_SEC"1"
MATERIAL"X6S"
TOLERANCE"20%"
VALUE"22UF"
VOLTAGE"4V"
PACK_TYPE"C0402"
CDS_LIB"pure_quanta"
PART_NUMBER"CH622KMEB02";
"B"
$PN"2"29;
"A"
$PN"1"28;
%"Q_CAP"
"1","(5875,5075)","0","pure_quanta","I141";
;
LOCATION"C2105"
$SEC"1"
CDS_SEC"1"
MATERIAL"X6S"
TOLERANCE"20%"
VALUE"22UF"
VOLTAGE"4V"
PACK_TYPE"C0402"
CDS_LIB"pure_quanta"
PART_NUMBER"CH622KMEB02";
"B"
$PN"2"31;
"A"
$PN"1"30;
%"Q_CAP"
"1","(5875,5875)","0","pure_quanta","I142";
;
LOCATION"C2104"
$SEC"1"
CDS_SEC"1"
MATERIAL"X6S"
TOLERANCE"20%"
VALUE"22UF"
VOLTAGE"4V"
PACK_TYPE"C0402"
CDS_LIB"pure_quanta"
PART_NUMBER"CH622KMEB02";
"B"
$PN"2"29;
"A"
$PN"1"28;
%"UNIVERSAL_POWER"
"1","(4975,6150)","0","pure_quanta_power","I143";
;
HDL_POWER"PVDDIO_P1"
CDS_LIB"pure_quanta_power";
"A"28;
%"Q_CAP"
"1","(6350,4300)","0","pure_quanta","I144";
;
LOCATION"C2108"
$SEC"1"
CDS_SEC"1"
MATERIAL"X6S"
TOLERANCE"20%"
VALUE"22UF"
VOLTAGE"4V"
PACK_TYPE"C0402"
CDS_LIB"pure_quanta"
PART_NUMBER"CH622KMEB02";
"B"
$PN"2"27;
"A"
$PN"1"32;
%"Q_CAP"
"1","(6325,5075)","0","pure_quanta","I145";
;
LOCATION"C2107"
$SEC"1"
CDS_SEC"1"
MATERIAL"X6S"
TOLERANCE"20%"
VALUE"22UF"
VOLTAGE"4V"
PACK_TYPE"C0402"
CDS_LIB"pure_quanta"
PART_NUMBER"CH622KMEB02";
"B"
$PN"2"31;
"A"
$PN"1"30;
%"Q_CAP"
"1","(6325,5875)","0","pure_quanta","I146";
;
LOCATION"C2493"
$SEC"1"
CDS_SEC"1"
MATERIAL"X6S"
TOLERANCE"20%"
VALUE"22UF"
VOLTAGE"4V"
PACK_TYPE"C0402"
CDS_LIB"pure_quanta"
PART_NUMBER"CH622KMEB02";
"B"
$PN"2"29;
"A"
$PN"1"28;
%"Q_CAP"
"1","(6775,5075)","0","pure_quanta","I147";
;
LOCATION"C2498"
$SEC"1"
CDS_SEC"1"
MATERIAL"X6S"
TOLERANCE"20%"
VALUE"22UF"
VOLTAGE"4V"
PACK_TYPE"C0402"
CDS_LIB"pure_quanta"
PART_NUMBER"CH622KMEB02";
"B"
$PN"2"31;
"A"
$PN"1"30;
%"Q_CAP"
"1","(6775,5875)","0","pure_quanta","I148";
;
LOCATION"C2109"
$SEC"1"
CDS_SEC"1"
MATERIAL"X6S"
TOLERANCE"20%"
VALUE"22UF"
VOLTAGE"4V"
PACK_TYPE"C0402"
CDS_LIB"pure_quanta"
PART_NUMBER"CH622KMEB02";
"B"
$PN"2"29;
"A"
$PN"1"28;
%"Q_CAP"
"1","(7225,5075)","0","pure_quanta","I149";
;
LOCATION"C2111"
$SEC"1"
CDS_SEC"1"
MATERIAL"X6S"
TOLERANCE"20%"
VALUE"22UF"
VOLTAGE"4V"
PACK_TYPE"C0402"
CDS_LIB"pure_quanta"
PART_NUMBER"CH622KMEB02";
"B"
$PN"2"31;
"A"
$PN"1"30;
%"UNIVERSAL_POWER"
"1","(400,3425)","0","pure_quanta_power","I15";
;
HDL_POWER"PVDDCR_SOC_P1"
CDS_LIB"pure_quanta_power";
"A"10;
%"Q_CAP"
"1","(7675,5075)","0","pure_quanta","I150";
;
LOCATION"C2112"
$SEC"1"
CDS_SEC"1"
MATERIAL"X6S"
TOLERANCE"20%"
VALUE"22UF"
VOLTAGE"4V"
PACK_TYPE"C0402"
CDS_LIB"pure_quanta"
PART_NUMBER"CH622KMEB02";
"B"
$PN"2"31;
"A"
$PN"1"30;
%"Q_CAP"
"1","(7225,5875)","0","pure_quanta","I151";
;
LOCATION"C2110"
$SEC"1"
CDS_SEC"1"
MATERIAL"X6S"
TOLERANCE"20%"
VALUE"22UF"
VOLTAGE"4V"
PACK_TYPE"C0402"
CDS_LIB"pure_quanta"
PART_NUMBER"CH622KMEB02";
"B"
$PN"2"29;
"A"
$PN"1"28;
%"Q_CAP"
"1","(7675,5875)","0","pure_quanta","I152";
;
LOCATION"C2507"
$SEC"1"
CDS_SEC"1"
MATERIAL"X6S"
TOLERANCE"20%"
VALUE"22UF"
VOLTAGE"4V"
PACK_TYPE"C0402"
CDS_LIB"pure_quanta"
PART_NUMBER"CH622KMEB02";
"B"
$PN"2"29;
"A"
$PN"1"28;
%"Q_CAP"
"1","(8125,5075)","0","pure_quanta","I153";
;
LOCATION"C2117"
$SEC"1"
CDS_SEC"1"
MATERIAL"X6S"
TOLERANCE"20%"
VALUE"22UF"
VOLTAGE"4V"
PACK_TYPE"C0402"
CDS_LIB"pure_quanta"
PART_NUMBER"CH622KMEB02";
"B"
$PN"2"31;
"A"
$PN"1"30;
%"Q_CAP"
"1","(8125,5875)","0","pure_quanta","I154";
;
LOCATION"C2116"
$SEC"1"
CDS_SEC"1"
MATERIAL"X6S"
TOLERANCE"20%"
VALUE"22UF"
VOLTAGE"4V"
PACK_TYPE"C0402"
CDS_LIB"pure_quanta"
PART_NUMBER"CH622KMEB02";
"B"
$PN"2"29;
"A"
$PN"1"28;
%"Q_CAP"
"1","(8600,1375)","0","pure_quanta","I155";
;
LOCATION"C3921"
$SEC"1"
CDS_SEC"1"
MATERIAL"X6S"
TOLERANCE"20%"
VALUE"22UF"
VOLTAGE"4V"
PACK_TYPE"C0402"
CDS_LIB"pure_quanta"
PART_NUMBER"CH622KMEB02";
"B"
$PN"2"19;
"A"
$PN"1"18;
%"UNIVERSAL_GND"
"1","(9000,1000)","0","pure_quanta_power","I156";
;
CDS_LIB"pure_quanta_power"
HDL_POWER"GND";
"A"19;
%"Q_CAP"
"1","(9000,1375)","0","pure_quanta","I157";
;
LOCATION"C3922"
$SEC"1"
CDS_SEC"1"
MATERIAL"X6S"
TOLERANCE"20%"
VALUE"22UF"
VOLTAGE"4V"
PACK_TYPE"C0402"
CDS_LIB"pure_quanta"
PART_NUMBER"CH622KMEB02";
"B"
$PN"2"19;
"A"
$PN"1"18;
%"UNIVERSAL_GND"
"1","(9000,1650)","0","pure_quanta_power","I158";
;
CDS_LIB"pure_quanta_power"
HDL_POWER"GND";
"A"17;
%"Q_CAP"
"1","(8600,2025)","0","pure_quanta","I159";
;
LOCATION"C2126"
$SEC"1"
CDS_SEC"1"
MATERIAL"X6S"
TOLERANCE"20%"
VALUE"22UF"
VOLTAGE"4V"
PACK_TYPE"C0402"
CDS_LIB"pure_quanta"
PART_NUMBER"CH622KMEB02";
"B"
$PN"2"17;
"A"
$PN"1"26;
%"Q_CAP"
"1","(400,3850)","0","pure_quanta","I16";
;
LOCATION"C2410"
$SEC"1"
CDS_SEC"1"
MATERIAL"X6S"
TOLERANCE"20%"
VALUE"22UF"
VOLTAGE"4V"
PACK_TYPE"C0402"
CDS_LIB"pure_quanta"
PART_NUMBER"CH622KMEB02";
"B"
$PN"2"9;
"A"
$PN"1"8;
%"Q_CAP"
"1","(8600,2650)","0","pure_quanta","I160";
;
LOCATION"C2125"
$SEC"1"
CDS_SEC"1"
MATERIAL"X6S"
TOLERANCE"20%"
VALUE"22UF"
VOLTAGE"4V"
PACK_TYPE"C0402"
CDS_LIB"pure_quanta"
PART_NUMBER"CH622KMEB02";
"B"
$PN"2"25;
"A"
$PN"1"24;
%"Q_CAP"
"1","(9000,2025)","0","pure_quanta","I161";
;
LOCATION"C2511"
$SEC"1"
CDS_SEC"1"
MATERIAL"X6S"
TOLERANCE"20%"
VALUE"22UF"
VOLTAGE"4V"
PACK_TYPE"C0402"
CDS_LIB"pure_quanta"
PART_NUMBER"CH622KMEB02";
"B"
$PN"2"17;
"A"
$PN"1"26;
%"UNIVERSAL_GND"
"1","(9000,2300)","0","pure_quanta_power","I162";
;
CDS_LIB"pure_quanta_power"
HDL_POWER"GND";
"A"25;
%"Q_CAP"
"1","(9000,2650)","0","pure_quanta","I163";
;
LOCATION"C2510"
$SEC"1"
CDS_SEC"1"
MATERIAL"X6S"
TOLERANCE"20%"
VALUE"22UF"
VOLTAGE"4V"
PACK_TYPE"C0402"
CDS_LIB"pure_quanta"
PART_NUMBER"CH622KMEB02";
"B"
$PN"2"25;
"A"
$PN"1"24;
%"Q_CAP"
"1","(8600,3325)","0","pure_quanta","I164";
;
LOCATION"C2124"
$SEC"1"
CDS_SEC"1"
MATERIAL"X6S"
TOLERANCE"20%"
VALUE"22UF"
VOLTAGE"4V"
PACK_TYPE"C0402"
CDS_LIB"pure_quanta"
PART_NUMBER"CH622KMEB02";
"B"
$PN"2"23;
"A"
$PN"1"22;
%"UNIVERSAL_GND"
"1","(9000,2950)","0","pure_quanta_power","I165";
;
CDS_LIB"pure_quanta_power"
HDL_POWER"GND";
"A"23;
%"Q_CAP"
"1","(9000,3325)","0","pure_quanta","I166";
;
LOCATION"C2128"
$SEC"1"
CDS_SEC"1"
MATERIAL"X6S"
TOLERANCE"20%"
VALUE"22UF"
VOLTAGE"4V"
PACK_TYPE"C0402"
CDS_LIB"pure_quanta"
PART_NUMBER"CH622KMEB02";
"B"
$PN"2"23;
"A"
$PN"1"22;
%"UNIVERSAL_GND"
"1","(8975,4700)","0","pure_quanta_power","I167";
;
CDS_LIB"pure_quanta_power"
HDL_POWER"GND";
"A"31;
%"Q_CAP"
"1","(8575,5075)","0","pure_quanta","I168";
;
LOCATION"C2123"
$SEC"1"
CDS_SEC"1"
MATERIAL"X6S"
TOLERANCE"20%"
VALUE"22UF"
VOLTAGE"4V"
PACK_TYPE"C0402"
CDS_LIB"pure_quanta"
PART_NUMBER"CH622KMEB02";
"B"
$PN"2"31;
"A"
$PN"1"30;
%"Q_CAP"
"1","(8575,5875)","0","pure_quanta","I169";
;
LOCATION"C2122"
$SEC"1"
CDS_SEC"1"
MATERIAL"X6S"
TOLERANCE"20%"
VALUE"22UF"
VOLTAGE"4V"
PACK_TYPE"C0402"
CDS_LIB"pure_quanta"
PART_NUMBER"CH622KMEB02";
"B"
$PN"2"29;
"A"
$PN"1"28;
%"Q_CAP"
"1","(850,3150)","0","pure_quanta","I17";
;
LOCATION"C2418"
$SEC"1"
CDS_SEC"1"
MATERIAL"X6S"
TOLERANCE"20%"
VALUE"22UF"
VOLTAGE"4V"
PACK_TYPE"C0402"
CDS_LIB"pure_quanta"
PART_NUMBER"CH622KMEB02";
"B"
$PN"2"5;
"A"
$PN"1"10;
%"Q_CAP"
"1","(8975,5075)","0","pure_quanta","I170";
;
LOCATION"C2509"
$SEC"1"
CDS_SEC"1"
MATERIAL"X6S"
TOLERANCE"20%"
VALUE"22UF"
VOLTAGE"4V"
PACK_TYPE"C0402"
CDS_LIB"pure_quanta"
PART_NUMBER"CH622KMEB02";
"B"
$PN"2"31;
"A"
$PN"1"30;
%"UNIVERSAL_GND"
"1","(8975,5500)","0","pure_quanta_power","I171";
;
CDS_LIB"pure_quanta_power"
HDL_POWER"GND";
"A"29;
%"Q_CAP"
"1","(8975,5875)","0","pure_quanta","I172";
;
LOCATION"C2127"
$SEC"1"
CDS_SEC"1"
MATERIAL"X6S"
TOLERANCE"20%"
VALUE"22UF"
VOLTAGE"4V"
PACK_TYPE"C0402"
CDS_LIB"pure_quanta"
PART_NUMBER"CH622KMEB02";
"B"
$PN"2"29;
"A"
$PN"1"28;
%"Q_CAP"
"1","(2650,5875)","0","pure_quanta","I173";
;
LOCATION"C2442"
$SEC"1"
CDS_SEC"1"
MATERIAL"X6S"
TOLERANCE"20%"
VALUE"22UF"
VOLTAGE"4V"
PACK_TYPE"C0402"
CDS_LIB"pure_quanta"
PART_NUMBER"CH622KMEB02";
"B"
$PN"2"15;
"A"
$PN"1"14;
%"Q_CAP"
"1","(2200,5875)","0","pure_quanta","I174";
;
LOCATION"C2435"
$SEC"1"
CDS_SEC"1"
MATERIAL"X6S"
TOLERANCE"20%"
VALUE"22UF"
VOLTAGE"4V"
PACK_TYPE"C0402"
CDS_LIB"pure_quanta"
PART_NUMBER"CH622KMEB02";
"B"
$PN"2"15;
"A"
$PN"1"14;
%"Q_CAP"
"1","(1750,5875)","0","pure_quanta","I175";
;
LOCATION"C2428"
$SEC"1"
CDS_SEC"1"
MATERIAL"X6S"
TOLERANCE"20%"
VALUE"22UF"
VOLTAGE"4V"
PACK_TYPE"C0402"
CDS_LIB"pure_quanta"
PART_NUMBER"CH622KMEB02";
"B"
$PN"2"15;
"A"
$PN"1"14;
%"Q_CAP"
"1","(850,3850)","0","pure_quanta","I18";
;
LOCATION"C2417"
$SEC"1"
CDS_SEC"1"
MATERIAL"X6S"
TOLERANCE"20%"
VALUE"22UF"
VOLTAGE"4V"
PACK_TYPE"C0402"
CDS_LIB"pure_quanta"
PART_NUMBER"CH622KMEB02";
"B"
$PN"2"9;
"A"
$PN"1"8;
%"Q_CAP"
"1","(1300,2475)","0","pure_quanta","I19";
;
LOCATION"C2426"
$SEC"1"
CDS_SEC"1"
MATERIAL"X6S"
TOLERANCE"20%"
VALUE"22UF"
VOLTAGE"4V"
PACK_TYPE"C0402"
CDS_LIB"pure_quanta"
PART_NUMBER"CH622KMEB02";
"B"
$PN"2"7;
"A"
$PN"1"6;
%"UNIVERSAL_POWER"
"1","(400,1350)","0","pure_quanta_power","I2";
;
HDL_POWER"PVDDCR_SOC_P1"
CDS_LIB"pure_quanta_power";
"A"4;
%"Q_CAP"
"1","(1750,2475)","0","pure_quanta","I20";
;
LOCATION"C2433"
$SEC"1"
CDS_SEC"1"
MATERIAL"X6S"
TOLERANCE"20%"
VALUE"22UF"
VOLTAGE"4V"
PACK_TYPE"C0402"
CDS_LIB"pure_quanta"
PART_NUMBER"CH622KMEB02";
"B"
$PN"2"7;
"A"
$PN"1"6;
%"Q_CAP"
"1","(1300,3150)","0","pure_quanta","I21";
;
LOCATION"C2425"
$SEC"1"
CDS_SEC"1"
MATERIAL"X6S"
TOLERANCE"20%"
VALUE"22UF"
VOLTAGE"4V"
PACK_TYPE"C0402"
CDS_LIB"pure_quanta"
PART_NUMBER"CH622KMEB02";
"B"
$PN"2"5;
"A"
$PN"1"10;
%"Q_CAP"
"1","(1300,3850)","0","pure_quanta","I22";
;
LOCATION"C2424"
$SEC"1"
CDS_SEC"1"
MATERIAL"X6S"
TOLERANCE"20%"
VALUE"22UF"
VOLTAGE"4V"
PACK_TYPE"C0402"
CDS_LIB"pure_quanta"
PART_NUMBER"CH622KMEB02";
"B"
$PN"2"9;
"A"
$PN"1"8;
%"Q_CAP"
"1","(1750,3150)","0","pure_quanta","I23";
;
LOCATION"C2432"
$SEC"1"
CDS_SEC"1"
MATERIAL"X6S"
TOLERANCE"20%"
VALUE"22UF"
VOLTAGE"4V"
PACK_TYPE"C0402"
CDS_LIB"pure_quanta"
PART_NUMBER"CH622KMEB02";
"B"
$PN"2"5;
"A"
$PN"1"10;
%"Q_CAP"
"1","(1750,3850)","0","pure_quanta","I24";
;
LOCATION"C2431"
$SEC"1"
CDS_SEC"1"
MATERIAL"X6S"
TOLERANCE"20%"
VALUE"22UF"
VOLTAGE"4V"
PACK_TYPE"C0402"
CDS_LIB"pure_quanta"
PART_NUMBER"CH622KMEB02";
"B"
$PN"2"9;
"A"
$PN"1"8;
%"Q_CAP"
"1","(2200,1075)","0","pure_quanta","I25";
;
LOCATION"C3916"
$SEC"1"
CDS_SEC"1"
MATERIAL"X6S"
TOLERANCE"20%"
VALUE"22UF"
VOLTAGE"4V"
PACK_TYPE"C0402"
CDS_LIB"pure_quanta"
PART_NUMBER"CH622KMEB02";
"B"
$PN"2"1;
"A"
$PN"1"4;
%"Q_CAP"
"1","(2200,1800)","0","pure_quanta","I26";
;
LOCATION"C2441"
$SEC"1"
CDS_SEC"1"
MATERIAL"X6S"
TOLERANCE"20%"
VALUE"22UF"
VOLTAGE"4V"
PACK_TYPE"C0402"
CDS_LIB"pure_quanta"
PART_NUMBER"CH622KMEB02";
"B"
$PN"2"3;
"A"
$PN"1"2;
%"Q_CAP"
"1","(2650,1075)","0","pure_quanta","I27";
;
LOCATION"C3917"
$SEC"1"
CDS_SEC"1"
MATERIAL"X6S"
TOLERANCE"20%"
VALUE"22UF"
VOLTAGE"4V"
PACK_TYPE"C0402"
CDS_LIB"pure_quanta"
PART_NUMBER"CH622KMEB02";
"B"
$PN"2"1;
"A"
$PN"1"4;
%"Q_CAP"
"1","(2650,1800)","0","pure_quanta","I28";
;
LOCATION"C2448"
$SEC"1"
CDS_SEC"1"
MATERIAL"X6S"
TOLERANCE"20%"
VALUE"22UF"
VOLTAGE"4V"
PACK_TYPE"C0402"
CDS_LIB"pure_quanta"
PART_NUMBER"CH622KMEB02";
"B"
$PN"2"3;
"A"
$PN"1"2;
%"Q_CAP"
"1","(3100,1800)","0","pure_quanta","I29";
;
LOCATION"C2455"
$SEC"1"
CDS_SEC"1"
MATERIAL"X6S"
TOLERANCE"20%"
VALUE"22UF"
VOLTAGE"4V"
PACK_TYPE"C0402"
CDS_LIB"pure_quanta"
PART_NUMBER"CH622KMEB02";
"B"
$PN"2"3;
"A"
$PN"1"2;
%"Q_CAP"
"1","(400,1800)","0","pure_quanta","I3";
;
LOCATION"C2413"
$SEC"1"
CDS_SEC"1"
MATERIAL"X6S"
TOLERANCE"20%"
VALUE"22UF"
VOLTAGE"4V"
PACK_TYPE"C0402"
CDS_LIB"pure_quanta"
PART_NUMBER"CH622KMEB02";
"B"
$PN"2"3;
"A"
$PN"1"2;
%"Q_CAP"
"1","(3100,1075)","0","pure_quanta","I30";
;
LOCATION"C3918"
$SEC"1"
CDS_SEC"1"
MATERIAL"X6S"
TOLERANCE"20%"
VALUE"22UF"
VOLTAGE"4V"
PACK_TYPE"C0402"
CDS_LIB"pure_quanta"
PART_NUMBER"CH622KMEB02";
"B"
$PN"2"1;
"A"
$PN"1"4;
%"UNIVERSAL_GND"
"1","(3100,700)","0","pure_quanta_power","I31";
;
CDS_LIB"pure_quanta_power"
HDL_POWER"GND";
"A"1;
%"Q_CAP"
"1","(3550,1800)","0","pure_quanta","I32";
;
LOCATION"C2462"
$SEC"1"
CDS_SEC"1"
MATERIAL"X6S"
TOLERANCE"20%"
VALUE"22UF"
VOLTAGE"4V"
PACK_TYPE"C0402"
CDS_LIB"pure_quanta"
PART_NUMBER"CH622KMEB02";
"B"
$PN"2"3;
"A"
$PN"1"2;
%"Q_CAP"
"1","(4000,1800)","0","pure_quanta","I33";
;
LOCATION"C2469"
$SEC"1"
CDS_SEC"1"
MATERIAL"X6S"
TOLERANCE"20%"
VALUE"22UF"
VOLTAGE"4V"
PACK_TYPE"C0402"
CDS_LIB"pure_quanta"
PART_NUMBER"CH622KMEB02";
"B"
$PN"2"3;
"A"
$PN"1"2;
%"Q_CAP"
"1","(2200,2475)","0","pure_quanta","I34";
;
LOCATION"C2440"
$SEC"1"
CDS_SEC"1"
MATERIAL"X6S"
TOLERANCE"20%"
VALUE"22UF"
VOLTAGE"4V"
PACK_TYPE"C0402"
CDS_LIB"pure_quanta"
PART_NUMBER"CH622KMEB02";
"B"
$PN"2"7;
"A"
$PN"1"6;
%"Q_CAP"
"1","(2650,2475)","0","pure_quanta","I35";
;
LOCATION"C2447"
$SEC"1"
CDS_SEC"1"
MATERIAL"X6S"
TOLERANCE"20%"
VALUE"22UF"
VOLTAGE"4V"
PACK_TYPE"C0402"
CDS_LIB"pure_quanta"
PART_NUMBER"CH622KMEB02";
"B"
$PN"2"7;
"A"
$PN"1"6;
%"Q_CAP"
"1","(2200,3150)","0","pure_quanta","I36";
;
LOCATION"C2439"
$SEC"1"
CDS_SEC"1"
MATERIAL"X6S"
TOLERANCE"20%"
VALUE"22UF"
VOLTAGE"4V"
PACK_TYPE"C0402"
CDS_LIB"pure_quanta"
PART_NUMBER"CH622KMEB02";
"B"
$PN"2"5;
"A"
$PN"1"10;
%"Q_CAP"
"1","(2200,3850)","0","pure_quanta","I37";
;
LOCATION"C2438"
$SEC"1"
CDS_SEC"1"
MATERIAL"X6S"
TOLERANCE"20%"
VALUE"22UF"
VOLTAGE"4V"
PACK_TYPE"C0402"
CDS_LIB"pure_quanta"
PART_NUMBER"CH622KMEB02";
"B"
$PN"2"9;
"A"
$PN"1"8;
%"Q_CAP"
"1","(2650,3150)","0","pure_quanta","I38";
;
LOCATION"C2446"
$SEC"1"
CDS_SEC"1"
MATERIAL"X6S"
TOLERANCE"20%"
VALUE"22UF"
VOLTAGE"4V"
PACK_TYPE"C0402"
CDS_LIB"pure_quanta"
PART_NUMBER"CH622KMEB02";
"B"
$PN"2"5;
"A"
$PN"1"10;
%"Q_CAP"
"1","(2650,3850)","0","pure_quanta","I39";
;
LOCATION"C2445"
$SEC"1"
CDS_SEC"1"
MATERIAL"X6S"
TOLERANCE"20%"
VALUE"22UF"
VOLTAGE"4V"
PACK_TYPE"C0402"
CDS_LIB"pure_quanta"
PART_NUMBER"CH622KMEB02";
"B"
$PN"2"9;
"A"
$PN"1"8;
%"Q_CAP"
"1","(850,1075)","0","pure_quanta","I4";
;
LOCATION"C3913"
$SEC"1"
CDS_SEC"1"
MATERIAL"X6S"
TOLERANCE"20%"
VALUE"22UF"
VOLTAGE"4V"
PACK_TYPE"C0402"
CDS_LIB"pure_quanta"
PART_NUMBER"CH622KMEB02";
"B"
$PN"2"1;
"A"
$PN"1"4;
%"Q_CAP"
"1","(3100,3850)","0","pure_quanta","I40";
;
LOCATION"C2452"
$SEC"1"
CDS_SEC"1"
MATERIAL"X6S"
TOLERANCE"20%"
VALUE"22UF"
VOLTAGE"4V"
PACK_TYPE"C0402"
CDS_LIB"pure_quanta"
PART_NUMBER"CH622KMEB02";
"B"
$PN"2"9;
"A"
$PN"1"8;
%"Q_CAP"
"1","(3100,3150)","0","pure_quanta","I41";
;
LOCATION"C2453"
$SEC"1"
CDS_SEC"1"
MATERIAL"X6S"
TOLERANCE"20%"
VALUE"22UF"
VOLTAGE"4V"
PACK_TYPE"C0402"
CDS_LIB"pure_quanta"
PART_NUMBER"CH622KMEB02";
"B"
$PN"2"5;
"A"
$PN"1"10;
%"Q_CAP"
"1","(3100,2475)","0","pure_quanta","I42";
;
LOCATION"C2454"
$SEC"1"
CDS_SEC"1"
MATERIAL"X6S"
TOLERANCE"20%"
VALUE"22UF"
VOLTAGE"4V"
PACK_TYPE"C0402"
CDS_LIB"pure_quanta"
PART_NUMBER"CH622KMEB02";
"B"
$PN"2"7;
"A"
$PN"1"6;
%"Q_CAP"
"1","(3550,2475)","0","pure_quanta","I43";
;
LOCATION"C2461"
$SEC"1"
CDS_SEC"1"
MATERIAL"X6S"
TOLERANCE"20%"
VALUE"22UF"
VOLTAGE"4V"
PACK_TYPE"C0402"
CDS_LIB"pure_quanta"
PART_NUMBER"CH622KMEB02";
"B"
$PN"2"7;
"A"
$PN"1"6;
%"Q_CAP"
"1","(4000,2475)","0","pure_quanta","I44";
;
LOCATION"C2468"
$SEC"1"
CDS_SEC"1"
MATERIAL"X6S"
TOLERANCE"20%"
VALUE"22UF"
VOLTAGE"4V"
PACK_TYPE"C0402"
CDS_LIB"pure_quanta"
PART_NUMBER"CH622KMEB02";
"B"
$PN"2"7;
"A"
$PN"1"6;
%"Q_CAP"
"1","(3550,3150)","0","pure_quanta","I45";
;
LOCATION"C2460"
$SEC"1"
CDS_SEC"1"
MATERIAL"X6S"
TOLERANCE"20%"
VALUE"22UF"
VOLTAGE"4V"
PACK_TYPE"C0402"
CDS_LIB"pure_quanta"
PART_NUMBER"CH622KMEB02";
"B"
$PN"2"5;
"A"
$PN"1"10;
%"Q_CAP"
"1","(3550,3850)","0","pure_quanta","I46";
;
LOCATION"C2459"
$SEC"1"
CDS_SEC"1"
MATERIAL"X6S"
TOLERANCE"20%"
VALUE"22UF"
VOLTAGE"4V"
PACK_TYPE"C0402"
CDS_LIB"pure_quanta"
PART_NUMBER"CH622KMEB02";
"B"
$PN"2"9;
"A"
$PN"1"8;
%"Q_CAP"
"1","(4000,3150)","0","pure_quanta","I47";
;
LOCATION"C2467"
$SEC"1"
CDS_SEC"1"
MATERIAL"X6S"
TOLERANCE"20%"
VALUE"22UF"
VOLTAGE"4V"
PACK_TYPE"C0402"
CDS_LIB"pure_quanta"
PART_NUMBER"CH622KMEB02";
"B"
$PN"2"5;
"A"
$PN"1"10;
%"Q_CAP"
"1","(4000,3850)","0","pure_quanta","I48";
;
LOCATION"C2466"
$SEC"1"
CDS_SEC"1"
MATERIAL"X6S"
TOLERANCE"20%"
VALUE"22UF"
VOLTAGE"4V"
PACK_TYPE"C0402"
CDS_LIB"pure_quanta"
PART_NUMBER"CH622KMEB02";
"B"
$PN"2"9;
"A"
$PN"1"8;
%"UNIVERSAL_POWER"
"1","(400,4125)","0","pure_quanta_power","I49";
;
HDL_POWER"PVDDCR_SOC_P1"
CDS_LIB"pure_quanta_power";
"A"8;
%"Q_CAP"
"1","(850,1800)","0","pure_quanta","I5";
;
LOCATION"C2420"
$SEC"1"
CDS_SEC"1"
MATERIAL"X6S"
TOLERANCE"20%"
VALUE"22UF"
VOLTAGE"4V"
PACK_TYPE"C0402"
CDS_LIB"pure_quanta"
PART_NUMBER"CH622KMEB02";
"B"
$PN"2"3;
"A"
$PN"1"2;
%"Q_CAP"
"1","(400,4550)","0","pure_quanta","I50";
;
LOCATION"C2409"
$SEC"1"
CDS_SEC"1"
MATERIAL"X6S"
TOLERANCE"20%"
VALUE"22UF"
VOLTAGE"4V"
PACK_TYPE"C0402"
CDS_LIB"pure_quanta"
PART_NUMBER"CH622KMEB02";
"B"
$PN"2"12;
"A"
$PN"1"11;
%"UNIVERSAL_POWER"
"1","(400,4825)","0","pure_quanta_power","I51";
;
HDL_POWER"PVDDCR_SOC_P1"
CDS_LIB"pure_quanta_power";
"A"11;
%"Q_CAP"
"1","(850,4550)","0","pure_quanta","I52";
;
LOCATION"C2416"
$SEC"1"
CDS_SEC"1"
MATERIAL"X6S"
TOLERANCE"20%"
VALUE"22UF"
VOLTAGE"4V"
PACK_TYPE"C0402"
CDS_LIB"pure_quanta"
PART_NUMBER"CH622KMEB02";
"B"
$PN"2"12;
"A"
$PN"1"11;
%"Q_CAP"
"1","(400,5225)","0","pure_quanta","I53";
;
LOCATION"C2408"
$SEC"1"
CDS_SEC"1"
MATERIAL"X6S"
TOLERANCE"20%"
VALUE"22UF"
VOLTAGE"4V"
PACK_TYPE"C0402"
CDS_LIB"pure_quanta"
PART_NUMBER"CH622KMEB02";
"B"
$PN"2"13;
"A"
$PN"1"16;
%"UNIVERSAL_POWER"
"1","(400,5500)","0","pure_quanta_power","I54";
;
HDL_POWER"PVDDCR_SOC_P1"
CDS_LIB"pure_quanta_power";
"A"16;
%"Q_CAP"
"1","(400,5875)","0","pure_quanta","I55";
;
LOCATION"C2407"
$SEC"1"
CDS_SEC"1"
MATERIAL"X6S"
TOLERANCE"20%"
VALUE"22UF"
VOLTAGE"4V"
PACK_TYPE"C0402"
CDS_LIB"pure_quanta"
PART_NUMBER"CH622KMEB02";
"B"
$PN"2"15;
"A"
$PN"1"14;
%"Q_CAP"
"1","(850,5225)","0","pure_quanta","I56";
;
LOCATION"C2415"
$SEC"1"
CDS_SEC"1"
MATERIAL"X6S"
TOLERANCE"20%"
VALUE"22UF"
VOLTAGE"4V"
PACK_TYPE"C0402"
CDS_LIB"pure_quanta"
PART_NUMBER"CH622KMEB02";
"B"
$PN"2"13;
"A"
$PN"1"16;
%"Q_CAP"
"1","(850,5875)","0","pure_quanta","I57";
;
LOCATION"C2414"
$SEC"1"
CDS_SEC"1"
MATERIAL"X6S"
TOLERANCE"20%"
VALUE"22UF"
VOLTAGE"4V"
PACK_TYPE"C0402"
CDS_LIB"pure_quanta"
PART_NUMBER"CH622KMEB02";
"B"
$PN"2"15;
"A"
$PN"1"14;
%"Q_CAP"
"1","(1300,4550)","0","pure_quanta","I58";
;
LOCATION"C2423"
$SEC"1"
CDS_SEC"1"
MATERIAL"X6S"
TOLERANCE"20%"
VALUE"22UF"
VOLTAGE"4V"
PACK_TYPE"C0402"
CDS_LIB"pure_quanta"
PART_NUMBER"CH622KMEB02";
"B"
$PN"2"12;
"A"
$PN"1"11;
%"Q_CAP"
"1","(1750,4550)","0","pure_quanta","I59";
;
LOCATION"C2430"
$SEC"1"
CDS_SEC"1"
MATERIAL"X6S"
TOLERANCE"20%"
VALUE"22UF"
VOLTAGE"4V"
PACK_TYPE"C0402"
CDS_LIB"pure_quanta"
PART_NUMBER"CH622KMEB02";
"B"
$PN"2"12;
"A"
$PN"1"11;
%"Q_CAP"
"1","(1300,1075)","0","pure_quanta","I6";
;
LOCATION"C3914"
$SEC"1"
CDS_SEC"1"
MATERIAL"X6S"
TOLERANCE"20%"
VALUE"22UF"
VOLTAGE"4V"
PACK_TYPE"C0402"
CDS_LIB"pure_quanta"
PART_NUMBER"CH622KMEB02";
"B"
$PN"2"1;
"A"
$PN"1"4;
%"Q_CAP"
"1","(1300,5225)","0","pure_quanta","I60";
;
LOCATION"C2422"
$SEC"1"
CDS_SEC"1"
MATERIAL"X6S"
TOLERANCE"20%"
VALUE"22UF"
VOLTAGE"4V"
PACK_TYPE"C0402"
CDS_LIB"pure_quanta"
PART_NUMBER"CH622KMEB02";
"B"
$PN"2"13;
"A"
$PN"1"16;
%"Q_CAP"
"1","(1300,5875)","0","pure_quanta","I61";
;
LOCATION"C2421"
$SEC"1"
CDS_SEC"1"
MATERIAL"X6S"
TOLERANCE"20%"
VALUE"22UF"
VOLTAGE"4V"
PACK_TYPE"C0402"
CDS_LIB"pure_quanta"
PART_NUMBER"CH622KMEB02";
"B"
$PN"2"15;
"A"
$PN"1"14;
%"Q_CAP"
"1","(1750,5225)","0","pure_quanta","I62";
;
LOCATION"C2429"
$SEC"1"
CDS_SEC"1"
MATERIAL"X6S"
TOLERANCE"20%"
VALUE"22UF"
VOLTAGE"4V"
PACK_TYPE"C0402"
CDS_LIB"pure_quanta"
PART_NUMBER"CH622KMEB02";
"B"
$PN"2"13;
"A"
$PN"1"16;
%"UNIVERSAL_POWER"
"1","(400,6150)","0","pure_quanta_power","I63";
;
HDL_POWER"PVDDCR_SOC_P1"
CDS_LIB"pure_quanta_power";
"A"14;
%"Q_CAP"
"1","(2200,4550)","0","pure_quanta","I64";
;
LOCATION"C2437"
$SEC"1"
CDS_SEC"1"
MATERIAL"X6S"
TOLERANCE"20%"
VALUE"22UF"
VOLTAGE"4V"
PACK_TYPE"C0402"
CDS_LIB"pure_quanta"
PART_NUMBER"CH622KMEB02";
"B"
$PN"2"12;
"A"
$PN"1"11;
%"Q_CAP"
"1","(2650,4550)","0","pure_quanta","I65";
;
LOCATION"C2444"
$SEC"1"
CDS_SEC"1"
MATERIAL"X6S"
TOLERANCE"20%"
VALUE"22UF"
VOLTAGE"4V"
PACK_TYPE"C0402"
CDS_LIB"pure_quanta"
PART_NUMBER"CH622KMEB02";
"B"
$PN"2"12;
"A"
$PN"1"11;
%"Q_CAP"
"1","(2200,5225)","0","pure_quanta","I66";
;
LOCATION"C2436"
$SEC"1"
CDS_SEC"1"
MATERIAL"X6S"
TOLERANCE"20%"
VALUE"22UF"
VOLTAGE"4V"
PACK_TYPE"C0402"
CDS_LIB"pure_quanta"
PART_NUMBER"CH622KMEB02";
"B"
$PN"2"13;
"A"
$PN"1"16;
%"Q_CAP"
"1","(2650,5225)","0","pure_quanta","I67";
;
LOCATION"C2443"
$SEC"1"
CDS_SEC"1"
MATERIAL"X6S"
TOLERANCE"20%"
VALUE"22UF"
VOLTAGE"4V"
PACK_TYPE"C0402"
CDS_LIB"pure_quanta"
PART_NUMBER"CH622KMEB02";
"B"
$PN"2"13;
"A"
$PN"1"16;
%"Q_CAP"
"1","(3100,5875)","0","pure_quanta","I68";
;
LOCATION"C2449"
$SEC"1"
CDS_SEC"1"
MATERIAL"X6S"
TOLERANCE"20%"
VALUE"22UF"
VOLTAGE"4V"
PACK_TYPE"C0402"
CDS_LIB"pure_quanta"
PART_NUMBER"CH622KMEB02";
"B"
$PN"2"15;
"A"
$PN"1"14;
%"Q_CAP"
"1","(3100,5225)","0","pure_quanta","I69";
;
LOCATION"C2450"
$SEC"1"
CDS_SEC"1"
MATERIAL"X6S"
TOLERANCE"20%"
VALUE"22UF"
VOLTAGE"4V"
PACK_TYPE"C0402"
CDS_LIB"pure_quanta"
PART_NUMBER"CH622KMEB02";
"B"
$PN"2"13;
"A"
$PN"1"16;
%"Q_CAP"
"1","(1300,1800)","0","pure_quanta","I7";
;
LOCATION"C2427"
$SEC"1"
CDS_SEC"1"
MATERIAL"X6S"
TOLERANCE"20%"
VALUE"22UF"
VOLTAGE"4V"
PACK_TYPE"C0402"
CDS_LIB"pure_quanta"
PART_NUMBER"CH622KMEB02";
"B"
$PN"2"3;
"A"
$PN"1"2;
%"Q_CAP"
"1","(3100,4550)","0","pure_quanta","I70";
;
LOCATION"C2451"
$SEC"1"
CDS_SEC"1"
MATERIAL"X6S"
TOLERANCE"20%"
VALUE"22UF"
VOLTAGE"4V"
PACK_TYPE"C0402"
CDS_LIB"pure_quanta"
PART_NUMBER"CH622KMEB02";
"B"
$PN"2"12;
"A"
$PN"1"11;
%"Q_CAP"
"1","(3550,4550)","0","pure_quanta","I71";
;
LOCATION"C2458"
$SEC"1"
CDS_SEC"1"
MATERIAL"X6S"
TOLERANCE"20%"
VALUE"22UF"
VOLTAGE"4V"
PACK_TYPE"C0402"
CDS_LIB"pure_quanta"
PART_NUMBER"CH622KMEB02";
"B"
$PN"2"12;
"A"
$PN"1"11;
%"Q_CAP"
"1","(4000,4550)","0","pure_quanta","I72";
;
LOCATION"C2465"
$SEC"1"
CDS_SEC"1"
MATERIAL"X6S"
TOLERANCE"20%"
VALUE"22UF"
VOLTAGE"4V"
PACK_TYPE"C0402"
CDS_LIB"pure_quanta"
PART_NUMBER"CH622KMEB02";
"B"
$PN"2"12;
"A"
$PN"1"11;
%"Q_CAP"
"1","(3550,5225)","0","pure_quanta","I73";
;
LOCATION"C2457"
$SEC"1"
CDS_SEC"1"
MATERIAL"X6S"
TOLERANCE"20%"
VALUE"22UF"
VOLTAGE"4V"
PACK_TYPE"C0402"
CDS_LIB"pure_quanta"
PART_NUMBER"CH622KMEB02";
"B"
$PN"2"13;
"A"
$PN"1"16;
%"Q_CAP"
"1","(3550,5875)","0","pure_quanta","I74";
;
LOCATION"C2456"
$SEC"1"
CDS_SEC"1"
MATERIAL"X6S"
TOLERANCE"20%"
VALUE"22UF"
VOLTAGE"4V"
PACK_TYPE"C0402"
CDS_LIB"pure_quanta"
PART_NUMBER"CH622KMEB02";
"B"
$PN"2"15;
"A"
$PN"1"14;
%"Q_CAP"
"1","(4000,5225)","0","pure_quanta","I75";
;
LOCATION"C2464"
$SEC"1"
CDS_SEC"1"
MATERIAL"X6S"
TOLERANCE"20%"
VALUE"22UF"
VOLTAGE"4V"
PACK_TYPE"C0402"
CDS_LIB"pure_quanta"
PART_NUMBER"CH622KMEB02";
"B"
$PN"2"13;
"A"
$PN"1"16;
%"Q_CAP"
"1","(4000,5875)","0","pure_quanta","I76";
;
LOCATION"C2463"
$SEC"1"
CDS_SEC"1"
MATERIAL"X6S"
TOLERANCE"20%"
VALUE"22UF"
VOLTAGE"4V"
PACK_TYPE"C0402"
CDS_LIB"pure_quanta"
PART_NUMBER"CH622KMEB02";
"B"
$PN"2"15;
"A"
$PN"1"14;
%"Q_CAP"
"1","(5000,775)","0","pure_quanta","I77";
;
LOCATION"C3919"
$SEC"1"
CDS_SEC"1"
MATERIAL"X6S"
TOLERANCE"20%"
VALUE"22UF"
VOLTAGE"4V"
PACK_TYPE"C0402"
CDS_LIB"pure_quanta"
PART_NUMBER"CH622KMEB02";
"B"
$PN"2"21;
"A"
$PN"1"20;
%"UNIVERSAL_GND"
"1","(4400,1425)","0","pure_quanta_power","I78";
;
CDS_LIB"pure_quanta_power"
HDL_POWER"GND";
"A"3;
%"Q_CAP"
"1","(4400,1800)","0","pure_quanta","I79";
;
LOCATION"C2476"
$SEC"1"
CDS_SEC"1"
MATERIAL"X6S"
TOLERANCE"20%"
VALUE"22UF"
VOLTAGE"4V"
PACK_TYPE"C0402"
CDS_LIB"pure_quanta"
PART_NUMBER"CH622KMEB02";
"B"
$PN"2"3;
"A"
$PN"1"2;
%"Q_CAP"
"1","(1750,1075)","0","pure_quanta","I8";
;
LOCATION"C3915"
$SEC"1"
CDS_SEC"1"
MATERIAL"X6S"
TOLERANCE"20%"
VALUE"22UF"
VOLTAGE"4V"
PACK_TYPE"C0402"
CDS_LIB"pure_quanta"
PART_NUMBER"CH622KMEB02";
"B"
$PN"2"1;
"A"
$PN"1"4;
%"UNIVERSAL_POWER"
"1","(5000,1050)","0","pure_quanta_power","I80";
;
HDL_POWER"PVDD11_S3_P1"
CDS_LIB"pure_quanta_power";
"A"20;
%"Q_CAP"
"1","(5000,1375)","0","pure_quanta","I81";
;
LOCATION"C2483"
$SEC"1"
CDS_SEC"1"
MATERIAL"X6S"
TOLERANCE"20%"
VALUE"22UF"
VOLTAGE"4V"
PACK_TYPE"C0402"
CDS_LIB"pure_quanta"
PART_NUMBER"CH622KMEB02";
"B"
$PN"2"19;
"A"
$PN"1"18;
%"UNIVERSAL_POWER"
"1","(5000,1650)","0","pure_quanta_power","I82";
;
HDL_POWER"PVDD11_S3_P1"
CDS_LIB"pure_quanta_power";
"A"18;
%"UNIVERSAL_GND"
"1","(5450,450)","0","pure_quanta_power","I83";
;
CDS_LIB"pure_quanta_power"
HDL_POWER"GND";
"A"21;
%"Q_CAP"
"1","(5450,775)","0","pure_quanta","I84";
;
LOCATION"C3920"
$SEC"1"
CDS_SEC"1"
MATERIAL"X6S"
TOLERANCE"20%"
VALUE"22UF"
VOLTAGE"4V"
PACK_TYPE"C0402"
CDS_LIB"pure_quanta"
PART_NUMBER"CH622KMEB02";
"B"
$PN"2"21;
"A"
$PN"1"20;
%"Q_CAP"
"1","(5450,1375)","0","pure_quanta","I85";
;
LOCATION"C2488"
$SEC"1"
CDS_SEC"1"
MATERIAL"X6S"
TOLERANCE"20%"
VALUE"22UF"
VOLTAGE"4V"
PACK_TYPE"C0402"
CDS_LIB"pure_quanta"
PART_NUMBER"CH622KMEB02";
"B"
$PN"2"19;
"A"
$PN"1"18;
%"Q_CAP"
"1","(5900,1375)","0","pure_quanta","I86";
;
LOCATION"C2492"
$SEC"1"
CDS_SEC"1"
MATERIAL"X6S"
TOLERANCE"20%"
VALUE"22UF"
VOLTAGE"4V"
PACK_TYPE"C0402"
CDS_LIB"pure_quanta"
PART_NUMBER"CH622KMEB02";
"B"
$PN"2"19;
"A"
$PN"1"18;
%"UNIVERSAL_GND"
"1","(4400,2100)","0","pure_quanta_power","I87";
;
CDS_LIB"pure_quanta_power"
HDL_POWER"GND";
"A"7;
%"Q_CAP"
"1","(4400,2475)","0","pure_quanta","I88";
;
LOCATION"C2475"
$SEC"1"
CDS_SEC"1"
MATERIAL"X6S"
TOLERANCE"20%"
VALUE"22UF"
VOLTAGE"4V"
PACK_TYPE"C0402"
CDS_LIB"pure_quanta"
PART_NUMBER"CH622KMEB02";
"B"
$PN"2"7;
"A"
$PN"1"6;
%"UNIVERSAL_GND"
"1","(4400,2775)","0","pure_quanta_power","I89";
;
CDS_LIB"pure_quanta_power"
HDL_POWER"GND";
"A"5;
%"Q_CAP"
"1","(1750,1800)","0","pure_quanta","I9";
;
LOCATION"C2434"
$SEC"1"
CDS_SEC"1"
MATERIAL"X6S"
TOLERANCE"20%"
VALUE"22UF"
VOLTAGE"4V"
PACK_TYPE"C0402"
CDS_LIB"pure_quanta"
PART_NUMBER"CH622KMEB02";
"B"
$PN"2"3;
"A"
$PN"1"2;
%"Q_CAP"
"1","(5000,2025)","0","pure_quanta","I90";
;
LOCATION"C2482"
$SEC"1"
CDS_SEC"1"
MATERIAL"X6S"
TOLERANCE"20%"
VALUE"22UF"
VOLTAGE"4V"
PACK_TYPE"C0402"
CDS_LIB"pure_quanta"
PART_NUMBER"CH622KMEB02";
"B"
$PN"2"17;
"A"
$PN"1"26;
%"UNIVERSAL_POWER"
"1","(5000,2300)","0","pure_quanta_power","I91";
;
HDL_POWER"PVDD11_S3_P1"
CDS_LIB"pure_quanta_power";
"A"26;
%"Q_CAP"
"1","(5000,2650)","0","pure_quanta","I92";
;
LOCATION"C2481"
$SEC"1"
CDS_SEC"1"
MATERIAL"X6S"
TOLERANCE"20%"
VALUE"22UF"
VOLTAGE"4V"
PACK_TYPE"C0402"
CDS_LIB"pure_quanta"
PART_NUMBER"CH622KMEB02";
"B"
$PN"2"25;
"A"
$PN"1"24;
%"UNIVERSAL_POWER"
"1","(5000,2925)","0","pure_quanta_power","I93";
;
HDL_POWER"PVDD11_S3_P1"
CDS_LIB"pure_quanta_power";
"A"24;
%"Q_CAP"
"1","(4400,3150)","0","pure_quanta","I94";
;
LOCATION"C2474"
$SEC"1"
CDS_SEC"1"
MATERIAL"X6S"
TOLERANCE"20%"
VALUE"22UF"
VOLTAGE"4V"
PACK_TYPE"C0402"
CDS_LIB"pure_quanta"
PART_NUMBER"CH622KMEB02";
"B"
$PN"2"5;
"A"
$PN"1"10;
%"UNIVERSAL_GND"
"1","(4400,3475)","0","pure_quanta_power","I95";
;
CDS_LIB"pure_quanta_power"
HDL_POWER"GND";
"A"9;
%"Q_CAP"
"1","(4400,3850)","0","pure_quanta","I96";
;
LOCATION"C2473"
$SEC"1"
CDS_SEC"1"
MATERIAL"X6S"
TOLERANCE"20%"
VALUE"22UF"
VOLTAGE"4V"
PACK_TYPE"C0402"
CDS_LIB"pure_quanta"
PART_NUMBER"CH622KMEB02";
"B"
$PN"2"9;
"A"
$PN"1"8;
%"Q_CAP"
"1","(5000,3325)","0","pure_quanta","I97";
;
LOCATION"C2480"
$SEC"1"
CDS_SEC"1"
MATERIAL"X6S"
TOLERANCE"20%"
VALUE"22UF"
VOLTAGE"4V"
PACK_TYPE"C0402"
CDS_LIB"pure_quanta"
PART_NUMBER"CH622KMEB02";
"B"
$PN"2"23;
"A"
$PN"1"22;
%"UNIVERSAL_POWER"
"1","(5000,3600)","0","pure_quanta_power","I98";
;
HDL_POWER"PVDD11_S3_P1"
CDS_LIB"pure_quanta_power";
"A"22;
%"Q_CAP"
"1","(5450,2025)","0","pure_quanta","I99";
;
LOCATION"C2487"
$SEC"1"
CDS_SEC"1"
MATERIAL"X6S"
TOLERANCE"20%"
VALUE"22UF"
VOLTAGE"4V"
PACK_TYPE"C0402"
CDS_LIB"pure_quanta"
PART_NUMBER"CH622KMEB02";
"B"
$PN"2"17;
"A"
$PN"1"26;
END.
